# T6G (Grand Teton) — schematic netlist excerpt (pin names and nets, part order shuffled) for the footprints in the layout excerpt that follows; sources: Cadence DE-HDL packaged netlist, KiCad conversion of 04192023_DAF0TMB3IC0_F0TG_MB_C_brd_V02_OCP.brd

R1413  Q_RES  1K 1% EMPTY  pkg 0201LF  page 309 : A = P1V8_CPU0_RT_1D ; B = RXDET_BYP_RT_CPU0_P3
C5016  Q_CAP  1000PF 50V 5% X7R  pkg 0402  page 226 : A = PWRGD_PVDD18_S5_R_P1 ; B = GND
R623  Q_RES  51.1 1% EMPTY  pkg 0201LF  page 276 : A = CLK_100M_RETIMER_CPU0_P0_DN ; B = GND

(kicad_pcb
	(version 20260206)
	(generator "pcbnew")
	(generator_version "10.0")
	(general
		(thickness 1.6)
		(legacy_teardrops no)
	)
	(paper "A4")
	(title_block
		(title "04192023_DAF0TMB3IC0_F0TG_MB_C_brd_V02_OCP.brd")
		(comment 1 "Grand Teton / footprints 2204-2206 of 8354")
	)
	(layers
		(0 "F.Cu" signal "TOP")
		(4 "In1.Cu" signal "GND")
		(6 "In2.Cu" signal "IN1")
		(8 "In3.Cu" signal "GND1")
		(10 "In4.Cu" signal "IN2")
		(12 "In5.Cu" signal "GND2")
		(14 "In6.Cu" signal "IN3")
		(16 "In7.Cu" signal "GND3")
		(18 "In8.Cu" signal "VCC")
		(20 "In9.Cu" signal "VCC1")
		(22 "In10.Cu" signal "GND4")
		(24 "In11.Cu" signal "IN4")
		(26 "In12.Cu" signal "GND5")
		(28 "In13.Cu" signal "IN5")
		(30 "In14.Cu" signal "GND6")
		(32 "In15.Cu" signal "IN6")
		(34 "In16.Cu" signal "GND7")
		(2 "B.Cu" signal "BOTTOM")
		(9 "F.Adhes" user "F.Adhesive")
		(11 "B.Adhes" user "B.Adhesive")
		(13 "F.Paste" user "Package Geometry/Pastemask Top")
		(15 "B.Paste" user "Package Geometry/Pastemask Bottom")
		(5 "F.SilkS" user "Ref Des/Silkscreen Top")
		(7 "B.SilkS" user "Ref Des/Silkscreen Bottom")
		(1 "F.Mask" user "Board Geometry/Soldermask Top")
		(3 "B.Mask" user "Board Geometry/Soldermask Bottom")
		(17 "Dwgs.User" user "User.Drawings")
		(19 "Cmts.User" user "User.Comments")
		(21 "Eco1.User" user "User.Eco1")
		(23 "Eco2.User" user "User.Eco2")
		(25 "Edge.Cuts" user "Board Geometry/Outline")
		(27 "Margin" user)
		(31 "F.CrtYd" user "Package Geometry/Place Bound Top")
		(29 "B.CrtYd" user "Package Geometry/Place Bound Bottom")
		(35 "F.Fab" user "Ref Des/Assembly Top")
		(33 "B.Fab" user "Ref Des/Assembly Bottom")
	)
	(footprint ""
		(layer "F.Cu")
		(at 205.25105 -107.362498)
		(property "Reference" "C5016"
			(at 0 0 0)
			(layer "F.SilkS")
			(hide yes)
			(effects
				(font
					(size 1.27 1.27)
				)
			)
		)
		(property "Value" ""
			(at 0 0 0)
			(layer "F.Fab")
			(effects
				(font
					(size 1.27 1.27)
				)
			)
		)
		(duplicate_pad_numbers_are_jumpers no)
		(fp_line
			(start -0.7874 -0.4064)
			(end 0.7874 -0.4064)
			(stroke
				(width 0.1524)
				(type default)
			)
			(layer "F.SilkS")
		)
		(fp_line
			(start -0.7874 0.4064)
			(end -0.7874 -0.4064)
			(stroke
				(width 0.1524)
				(type default)
			)
			(layer "F.SilkS")
		)
		(fp_line
			(start 0.7874 -0.4064)
			(end 0.7874 0.4064)
			(stroke
				(width 0.1524)
				(type default)
			)
			(layer "F.SilkS")
		)
		(fp_line
			(start 0.7874 0.4064)
			(end -0.7874 0.4064)
			(stroke
				(width 0.1524)
				(type default)
			)
			(layer "F.SilkS")
		)
		(fp_line
			(start -0.67945 -0.305054)
			(end -0.12065 -0.305054)
			(stroke
				(width 0.1)
				(type default)
			)
			(layer "F.Fab")
		)
		(fp_line
			(start -0.67945 0.3048)
			(end -0.67945 -0.305054)
			(stroke
				(width 0.1)
				(type default)
			)
			(layer "F.Fab")
		)
		(fp_line
			(start -0.12065 -0.305054)
			(end -0.12065 -0.2794)
			(stroke
				(width 0.1)
				(type default)
			)
			(layer "F.Fab")
		)
		(fp_line
			(start -0.12065 -0.2794)
			(end 0.12065 -0.2794)
			(stroke
				(width 0.1)
				(type default)
			)
			(layer "F.Fab")
		)
		(fp_line
			(start -0.12065 0.2794)
			(end -0.12065 0.3048)
			(stroke
				(width 0.1)
				(type default)
			)
			(layer "F.Fab")
		)
		(fp_line
			(start -0.12065 0.3048)
			(end -0.67945 0.3048)
			(stroke
				(width 0.1)
				(type default)
			)
			(layer "F.Fab")
		)
		(fp_line
			(start 0.120396 0.2794)
			(end -0.12065 0.2794)
			(stroke
				(width 0.1)
				(type default)
			)
			(layer "F.Fab")
		)
		(fp_line
			(start 0.120396 0.3048)
			(end 0.120396 0.2794)
			(stroke
				(width 0.1)
				(type default)
			)
			(layer "F.Fab")
		)
		(fp_line
			(start 0.12065 -0.3048)
			(end 0.67945 -0.3048)
			(stroke
				(width 0.1)
				(type default)
			)
			(layer "F.Fab")
		)
		(fp_line
			(start 0.12065 -0.2794)
			(end 0.12065 -0.3048)
			(stroke
				(width 0.1)
				(type default)
			)
			(layer "F.Fab")
		)
		(fp_line
			(start 0.67945 -0.3048)
			(end 0.67945 0.3048)
			(stroke
				(width 0.1)
				(type default)
			)
			(layer "F.Fab")
		)
		(fp_line
			(start 0.67945 0.3048)
			(end 0.120396 0.3048)
			(stroke
				(width 0.1)
				(type default)
			)
			(layer "F.Fab")
		)
		(pad "1" smd circle
			(at -0.40005 0)
			(size 0 0)
			(layers "F.Cu" "F.Mask" "F.Paste")
			(net "PWRGD_PVDD18_S5_R_P1")
		)
		(pad "2" smd circle
			(at 0.40005 0)
			(size 0 0)
			(layers "F.Cu" "F.Mask" "F.Paste")
			(net "GND")
		)
	)
	(footprint ""
		(layer "F.Cu")
		(at 398.069562 -397.726154 180)
		(property "Reference" "R1413"
			(at 0 0 180)
			(layer "F.SilkS")
			(hide yes)
			(effects
				(font
					(size 1.27 1.27)
				)
			)
		)
		(property "Value" ""
			(at 0 0 180)
			(layer "F.Fab")
			(effects
				(font
					(size 1.27 1.27)
				)
			)
		)
		(duplicate_pad_numbers_are_jumpers no)
		(fp_line
			(start 0.32512 0.175006)
			(end -0.32512 0.175006)
			(stroke
				(width 0.1)
				(type default)
			)
			(layer "F.Fab")
		)
		(fp_line
			(start 0.32512 -0.175006)
			(end 0.32512 0.175006)
			(stroke
				(width 0.1)
				(type default)
			)
			(layer "F.Fab")
		)
		(fp_line
			(start -0.32512 0.175006)
			(end -0.32512 -0.175006)
			(stroke
				(width 0.1)
				(type default)
			)
			(layer "F.Fab")
		)
		(fp_line
			(start -0.32512 -0.175006)
			(end 0.32512 -0.175006)
			(stroke
				(width 0.1)
				(type default)
			)
			(layer "F.Fab")
		)
		(pad "1" smd rect
			(at -0.2667 0 180)
			(size 0.3048 0.381)
			(layers "F.Cu" "F.Mask" "F.Paste")
			(net "P1V8_CPU0_RT_1D")
		)
		(pad "2" smd rect
			(at 0.2667 0)
			(size 0.3048 0.381)
			(layers "F.Cu" "F.Mask" "F.Paste")
			(net "RXDET_BYP_RT_CPU0_P3")
		)
	)
	(footprint ""
		(layer "F.Cu")
		(at 299.543724 -395.066774 -90)
		(property "Reference" "R623"
			(at 0 0 270)
			(layer "F.SilkS")
			(hide yes)
			(effects
				(font
					(size 1.27 1.27)
				)
			)
		)
		(property "Value" ""
			(at 0 0 270)
			(layer "F.Fab")
			(effects
				(font
					(size 1.27 1.27)
				)
			)
		)
		(duplicate_pad_numbers_are_jumpers no)
		(fp_line
			(start -0.32512 0.175006)
			(end -0.32512 -0.175006)
			(stroke
				(width 0.1)
				(type default)
			)
			(layer "F.Fab")
		)
		(fp_line
			(start 0.32512 0.175006)
			(end -0.32512 0.175006)
			(stroke
				(width 0.1)
				(type default)
			)
			(layer "F.Fab")
		)
		(fp_line
			(start -0.32512 -0.175006)
			(end 0.32512 -0.175006)
			(stroke
				(width 0.1)
				(type default)
			)
			(layer "F.Fab")
		)
		(fp_line
			(start 0.32512 -0.175006)
			(end 0.32512 0.175006)
			(stroke
				(width 0.1)
				(type default)
			)
			(layer "F.Fab")
		)
		(pad "1" smd rect
			(at -0.2667 0 270)
			(size 0.3048 0.381)
			(layers "F.Cu" "F.Mask" "F.Paste")
			(net "CLK_100M_RETIMER_CPU0_P0_DN")
		)
		(pad "2" smd rect
			(at 0.2667 0 90)
			(size 0.3048 0.381)
			(layers "F.Cu" "F.Mask" "F.Paste")
			(net "GND")
		)
	)
)
